# S9S_MB_2U (Grand Teton) — schematic netlist excerpt (pin names and nets, part order shuffled) for the footprints in the layout excerpt that follows; sources: Cadence DE-HDL packaged netlist, KiCad conversion of 03242023_DA0F0TMBIJ0_F0T_Motherboard_J_brd_V01_OCP.brd

C1008  Q_CAP  22UF 4V 20% X6S  pkg C0402  page 74 : A = PVCCIN_CPU0 ; B = GND

(kicad_pcb
	(version 20260206)
	(generator "pcbnew")
	(generator_version "10.0")
	(general
		(thickness 1.6)
		(legacy_teardrops no)
	)
	(paper "A4")
	(title_block
		(title "03242023_DA0F0TMBIJ0_F0T_Motherboard_J_brd_V01_OCP.brd")
		(comment 1 "Grand Teton / footprints 1293-1293 of 6105")
	)
	(layers
		(0 "F.Cu" signal "TOP")
		(4 "In1.Cu" signal "GND")
		(6 "In2.Cu" signal "IN1")
		(8 "In3.Cu" signal "GND1")
		(10 "In4.Cu" signal "IN2")
		(12 "In5.Cu" signal "GND2")
		(14 "In6.Cu" signal "IN3")
		(16 "In7.Cu" signal "GND3")
		(18 "In8.Cu" signal "VCC")
		(20 "In9.Cu" signal "VCC1")
		(22 "In10.Cu" signal "GND4")
		(24 "In11.Cu" signal "IN4")
		(26 "In12.Cu" signal "GND5")
		(28 "In13.Cu" signal "IN5")
		(30 "In14.Cu" signal "GND6")
		(32 "In15.Cu" signal "IN6")
		(34 "In16.Cu" signal "GND7")
		(2 "B.Cu" signal "BOTTOM")
		(9 "F.Adhes" user "F.Adhesive")
		(11 "B.Adhes" user "B.Adhesive")
		(13 "F.Paste" user "Package Geometry/Pastemask Top")
		(15 "B.Paste" user "Package Geometry/Pastemask Bottom")
		(5 "F.SilkS" user "Ref Des/Silkscreen Top")
		(7 "B.SilkS" user "Ref Des/Silkscreen Bottom")
		(1 "F.Mask" user "Board Geometry/Soldermask Top")
		(3 "B.Mask" user "Board Geometry/Soldermask Bottom")
		(17 "Dwgs.User" user "User.Drawings")
		(19 "Cmts.User" user "User.Comments")
		(21 "Eco1.User" user "User.Eco1")
		(23 "Eco2.User" user "User.Eco2")
		(25 "Edge.Cuts" user "Board Geometry/Outline")
		(27 "Margin" user)
		(31 "F.CrtYd" user "Package Geometry/Place Bound Top")
		(29 "B.CrtYd" user "Package Geometry/Place Bound Bottom")
		(35 "F.Fab" user "Ref Des/Assembly Top")
		(33 "B.Fab" user "Ref Des/Assembly Bottom")
	)
	(footprint ""
		(layer "F.Cu")
		(at 366.48263 -255.053846 90)
		(property "Reference" "C1008"
			(at 0 0 90)
			(layer "F.SilkS")
			(hide yes)
			(effects
				(font
					(size 1.27 1.27)
				)
			)
		)
		(property "Value" ""
			(at 0 0 90)
			(layer "F.Fab")
			(effects
				(font
					(size 1.27 1.27)
				)
			)
		)
		(duplicate_pad_numbers_are_jumpers no)
		(fp_line
			(start 0.7874 -0.4064)
			(end 0.7874 0.4064)
			(stroke
				(width 0.1524)
				(type default)
			)
			(layer "F.SilkS")
		)
		(fp_line
			(start -0.7874 -0.4064)
			(end 0.7874 -0.4064)
			(stroke
				(width 0.1524)
				(type default)
			)
			(layer "F.SilkS")
		)
		(fp_line
			(start 0.7874 0.4064)
			(end -0.7874 0.4064)
			(stroke
				(width 0.1524)
				(type default)
			)
			(layer "F.SilkS")
		)
		(fp_line
			(start -0.7874 0.4064)
			(end -0.7874 -0.4064)
			(stroke
				(width 0.1524)
				(type default)
			)
			(layer "F.SilkS")
		)
		(fp_line
			(start -0.12065 -0.305054)
			(end -0.12065 -0.2794)
			(stroke
				(width 0.1)
				(type default)
			)
			(layer "F.Fab")
		)
		(fp_line
			(start -0.67945 -0.305054)
			(end -0.12065 -0.305054)
			(stroke
				(width 0.1)
				(type default)
			)
			(layer "F.Fab")
		)
		(fp_line
			(start 0.67945 -0.3048)
			(end 0.67945 0.3048)
			(stroke
				(width 0.1)
				(type default)
			)
			(layer "F.Fab")
		)
		(fp_line
			(start 0.12065 -0.3048)
			(end 0.67945 -0.3048)
			(stroke
				(width 0.1)
				(type default)
			)
			(layer "F.Fab")
		)
		(fp_line
			(start 0.12065 -0.2794)
			(end 0.12065 -0.3048)
			(stroke
				(width 0.1)
				(type default)
			)
			(layer "F.Fab")
		)
		(fp_line
			(start -0.12065 -0.2794)
			(end 0.12065 -0.2794)
			(stroke
				(width 0.1)
				(type default)
			)
			(layer "F.Fab")
		)
		(fp_line
			(start 0.120396 0.2794)
			(end -0.12065 0.2794)
			(stroke
				(width 0.1)
				(type default)
			)
			(layer "F.Fab")
		)
		(fp_line
			(start -0.12065 0.2794)
			(end -0.12065 0.3048)
			(stroke
				(width 0.1)
				(type default)
			)
			(layer "F.Fab")
		)
		(fp_line
			(start 0.67945 0.3048)
			(end 0.120396 0.3048)
			(stroke
				(width 0.1)
				(type default)
			)
			(layer "F.Fab")
		)
		(fp_line
			(start 0.120396 0.3048)
			(end 0.120396 0.2794)
			(stroke
				(width 0.1)
				(type default)
			)
			(layer "F.Fab")
		)
		(fp_line
			(start -0.12065 0.3048)
			(end -0.67945 0.3048)
			(stroke
				(width 0.1)
				(type default)
			)
			(layer "F.Fab")
		)
		(fp_line
			(start -0.67945 0.3048)
			(end -0.67945 -0.305054)
			(stroke
				(width 0.1)
				(type default)
			)
			(layer "F.Fab")
		)
		(pad "1" smd circle
			(at -0.40005 0 90)
			(size 0 0)
			(layers "F.Cu" "F.Mask" "F.Paste")
			(net "PVCCIN_CPU0")
		)
		(pad "2" smd circle
			(at 0.40005 0 90)
			(size 0 0)
			(layers "F.Cu" "F.Mask" "F.Paste")
			(net "GND")
		)
	)
)
